# T6G (Grand Teton) — schematic netlist excerpt (pin names and nets, part order shuffled) for the footprints in the layout excerpt that follows; sources: Cadence DE-HDL packaged netlist, KiCad conversion of 04192023_DAF0TMB3IC0_F0TG_MB_C_brd_V02_OCP.brd

R2805  Q_RES  4.7K 5% EMPTY  pkg 0402LF  page 240 : A = P3V3_AUX ; B = SMB_FAN_3V3AUX_BUF_SCL
R486  Q_RES  0 5% CHIP  pkg 0402LF  page 54 : A = CPU1_XTRIG_R2_L4 ; B = CPU1_XTRIG_L4

(kicad_pcb
	(version 20260206)
	(generator "pcbnew")
	(generator_version "10.0")
	(general
		(thickness 1.6)
		(legacy_teardrops no)
	)
	(paper "A4")
	(title_block
		(title "04192023_DAF0TMB3IC0_F0TG_MB_C_brd_V02_OCP.brd")
		(comment 1 "Grand Teton / footprints 8319-8320 of 8354")
	)
	(layers
		(0 "F.Cu" signal "TOP")
		(4 "In1.Cu" signal "GND")
		(6 "In2.Cu" signal "IN1")
		(8 "In3.Cu" signal "GND1")
		(10 "In4.Cu" signal "IN2")
		(12 "In5.Cu" signal "GND2")
		(14 "In6.Cu" signal "IN3")
		(16 "In7.Cu" signal "GND3")
		(18 "In8.Cu" signal "VCC")
		(20 "In9.Cu" signal "VCC1")
		(22 "In10.Cu" signal "GND4")
		(24 "In11.Cu" signal "IN4")
		(26 "In12.Cu" signal "GND5")
		(28 "In13.Cu" signal "IN5")
		(30 "In14.Cu" signal "GND6")
		(32 "In15.Cu" signal "IN6")
		(34 "In16.Cu" signal "GND7")
		(2 "B.Cu" signal "BOTTOM")
		(9 "F.Adhes" user "F.Adhesive")
		(11 "B.Adhes" user "B.Adhesive")
		(13 "F.Paste" user "Package Geometry/Pastemask Top")
		(15 "B.Paste" user "Package Geometry/Pastemask Bottom")
		(5 "F.SilkS" user "Ref Des/Silkscreen Top")
		(7 "B.SilkS" user "Ref Des/Silkscreen Bottom")
		(1 "F.Mask" user "Board Geometry/Soldermask Top")
		(3 "B.Mask" user "Board Geometry/Soldermask Bottom")
		(17 "Dwgs.User" user "User.Drawings")
		(19 "Cmts.User" user "User.Comments")
		(21 "Eco1.User" user "User.Eco1")
		(23 "Eco2.User" user "User.Eco2")
		(25 "Edge.Cuts" user "Board Geometry/Outline")
		(27 "Margin" user)
		(31 "F.CrtYd" user "Package Geometry/Place Bound Top")
		(29 "B.CrtYd" user "Package Geometry/Place Bound Bottom")
		(35 "F.Fab" user "Ref Des/Assembly Top")
		(33 "B.Fab" user "Ref Des/Assembly Bottom")
	)
	(footprint ""
		(layer "B.Cu")
		(at 184.681114 -418.591238)
		(property "Reference" "R2805"
			(at 0 0 0)
			(layer "B.SilkS")
			(hide yes)
			(effects
				(font
					(size 1.27 1.27)
				)
				(justify mirror)
			)
		)
		(property "Value" ""
			(at 0 0 0)
			(layer "B.Fab")
			(effects
				(font
					(size 1.27 1.27)
				)
				(justify mirror)
			)
		)
		(duplicate_pad_numbers_are_jumpers no)
		(fp_line
			(start -0.7874 -0.4064)
			(end -0.7874 0.4064)
			(stroke
				(width 0.1524)
				(type default)
			)
			(layer "B.SilkS")
		)
		(fp_line
			(start -0.7874 0.4064)
			(end 0.7874 0.4064)
			(stroke
				(width 0.1524)
				(type default)
			)
			(layer "B.SilkS")
		)
		(fp_line
			(start 0.7874 -0.4064)
			(end -0.7874 -0.4064)
			(stroke
				(width 0.1524)
				(type default)
			)
			(layer "B.SilkS")
		)
		(fp_line
			(start 0.7874 0.4064)
			(end 0.7874 -0.4064)
			(stroke
				(width 0.1524)
				(type default)
			)
			(layer "B.SilkS")
		)
		(fp_line
			(start -0.67945 -0.3048)
			(end -0.67945 0.3048)
			(stroke
				(width 0.1)
				(type default)
			)
			(layer "B.Fab")
		)
		(fp_line
			(start -0.67945 0.3048)
			(end -0.120396 0.3048)
			(stroke
				(width 0.1)
				(type default)
			)
			(layer "B.Fab")
		)
		(fp_line
			(start -0.12065 -0.3048)
			(end -0.67945 -0.3048)
			(stroke
				(width 0.1)
				(type default)
			)
			(layer "B.Fab")
		)
		(fp_line
			(start -0.12065 -0.2794)
			(end -0.12065 -0.3048)
			(stroke
				(width 0.1)
				(type default)
			)
			(layer "B.Fab")
		)
		(fp_line
			(start -0.120396 0.2794)
			(end 0.12065 0.2794)
			(stroke
				(width 0.1)
				(type default)
			)
			(layer "B.Fab")
		)
		(fp_line
			(start -0.120396 0.3048)
			(end -0.120396 0.2794)
			(stroke
				(width 0.1)
				(type default)
			)
			(layer "B.Fab")
		)
		(fp_line
			(start 0.12065 -0.305054)
			(end 0.12065 -0.2794)
			(stroke
				(width 0.1)
				(type default)
			)
			(layer "B.Fab")
		)
		(fp_line
			(start 0.12065 -0.2794)
			(end -0.12065 -0.2794)
			(stroke
				(width 0.1)
				(type default)
			)
			(layer "B.Fab")
		)
		(fp_line
			(start 0.12065 0.2794)
			(end 0.12065 0.3048)
			(stroke
				(width 0.1)
				(type default)
			)
			(layer "B.Fab")
		)
		(fp_line
			(start 0.12065 0.3048)
			(end 0.67945 0.3048)
			(stroke
				(width 0.1)
				(type default)
			)
			(layer "B.Fab")
		)
		(fp_line
			(start 0.67945 -0.305054)
			(end 0.12065 -0.305054)
			(stroke
				(width 0.1)
				(type default)
			)
			(layer "B.Fab")
		)
		(fp_line
			(start 0.67945 0.3048)
			(end 0.67945 -0.305054)
			(stroke
				(width 0.1)
				(type default)
			)
			(layer "B.Fab")
		)
		(pad "1" smd circle
			(at 0.40005 0 180)
			(size 0 0)
			(layers "B.Cu" "B.Mask" "B.Paste")
			(net "P3V3_AUX")
		)
		(pad "2" smd circle
			(at -0.40005 0 180)
			(size 0 0)
			(layers "B.Cu" "B.Mask" "B.Paste")
			(net "SMB_FAN_3V3AUX_BUF_SCL")
		)
	)
	(footprint ""
		(layer "B.Cu")
		(at 92.281502 -207.38465 90)
		(property "Reference" "R486"
			(at 0 0 90)
			(layer "B.SilkS")
			(hide yes)
			(effects
				(font
					(size 1.27 1.27)
				)
				(justify mirror)
			)
		)
		(property "Value" ""
			(at 0 0 90)
			(layer "B.Fab")
			(effects
				(font
					(size 1.27 1.27)
				)
				(justify mirror)
			)
		)
		(duplicate_pad_numbers_are_jumpers no)
		(fp_line
			(start 0.7874 -0.4064)
			(end -0.7874 -0.4064)
			(stroke
				(width 0.1524)
				(type default)
			)
			(layer "B.SilkS")
		)
		(fp_line
			(start -0.7874 -0.4064)
			(end -0.7874 0.4064)
			(stroke
				(width 0.1524)
				(type default)
			)
			(layer "B.SilkS")
		)
		(fp_line
			(start 0.7874 0.4064)
			(end 0.7874 -0.4064)
			(stroke
				(width 0.1524)
				(type default)
			)
			(layer "B.SilkS")
		)
		(fp_line
			(start -0.7874 0.4064)
			(end 0.7874 0.4064)
			(stroke
				(width 0.1524)
				(type default)
			)
			(layer "B.SilkS")
		)
		(fp_line
			(start 0.67945 -0.305054)
			(end 0.12065 -0.305054)
			(stroke
				(width 0.1)
				(type default)
			)
			(layer "B.Fab")
		)
		(fp_line
			(start 0.12065 -0.305054)
			(end 0.12065 -0.2794)
			(stroke
				(width 0.1)
				(type default)
			)
			(layer "B.Fab")
		)
		(fp_line
			(start -0.12065 -0.3048)
			(end -0.67945 -0.3048)
			(stroke
				(width 0.1)
				(type default)
			)
			(layer "B.Fab")
		)
		(fp_line
			(start -0.67945 -0.3048)
			(end -0.67945 0.3048)
			(stroke
				(width 0.1)
				(type default)
			)
			(layer "B.Fab")
		)
		(fp_line
			(start 0.12065 -0.2794)
			(end -0.12065 -0.2794)
			(stroke
				(width 0.1)
				(type default)
			)
			(layer "B.Fab")
		)
		(fp_line
			(start -0.12065 -0.2794)
			(end -0.12065 -0.3048)
			(stroke
				(width 0.1)
				(type default)
			)
			(layer "B.Fab")
		)
		(fp_line
			(start 0.12065 0.2794)
			(end 0.12065 0.3048)
			(stroke
				(width 0.1)
				(type default)
			)
			(layer "B.Fab")
		)
		(fp_line
			(start -0.120396 0.2794)
			(end 0.12065 0.2794)
			(stroke
				(width 0.1)
				(type default)
			)
			(layer "B.Fab")
		)
		(fp_line
			(start 0.67945 0.3048)
			(end 0.67945 -0.305054)
			(stroke
				(width 0.1)
				(type default)
			)
			(layer "B.Fab")
		)
		(fp_line
			(start 0.12065 0.3048)
			(end 0.67945 0.3048)
			(stroke
				(width 0.1)
				(type default)
			)
			(layer "B.Fab")
		)
		(fp_line
			(start -0.120396 0.3048)
			(end -0.120396 0.2794)
			(stroke
				(width 0.1)
				(type default)
			)
			(layer "B.Fab")
		)
		(fp_line
			(start -0.67945 0.3048)
			(end -0.120396 0.3048)
			(stroke
				(width 0.1)
				(type default)
			)
			(layer "B.Fab")
		)
		(pad "1" smd circle
			(at 0.40005 0 270)
			(size 0 0)
			(layers "B.Cu" "B.Mask" "B.Paste")
			(net "CPU1_XTRIG_R2_L4")
		)
		(pad "2" smd circle
			(at -0.40005 0 270)
			(size 0 0)
			(layers "B.Cu" "B.Mask" "B.Paste")
			(net "CPU1_XTRIG_L4")
		)
	)
)
